# BASEBOARD_FAB2 (Tioga Pass) — schematic netlist excerpt (pin names and nets, part order shuffled) for the footprints in the layout excerpt that follows; sources: Cadence DE-HDL packaged netlist, KiCad conversion of Wiwynn_Tioga_Pass_MB.brd

C5D17  CAP_A  22.0UF 4V 20% X6S  pkg 0603V  page 42 : A = PVCCIN_CPU0 ; B = GND
R1E5  RES  1.00K 1% EMPTY  pkg 0402  page 209 : A = VSENSE_PVCCIN_CPU1_P ; B = VSENSE_PVCCIN_CPU1_N
R8B20  RES  10.0 1% CHIP  pkg 0402  page 114 : A = H_PMSYNC_CLK_24M_R ; B = H_PMSYNC_CLK_24M

(kicad_pcb
	(version 20260206)
	(generator "pcbnew")
	(generator_version "10.0")
	(general
		(thickness 1.6)
		(legacy_teardrops no)
	)
	(paper "A4")
	(title_block
		(title "Wiwynn_Tioga_Pass_MB.brd")
		(comment 1 "Tioga Pass / footprints 1978-1980 of 4770")
	)
	(layers
		(0 "F.Cu" signal "TOP")
		(4 "In1.Cu" signal "L2GND")
		(6 "In2.Cu" signal "L3")
		(8 "In3.Cu" signal "L4GND")
		(10 "In4.Cu" signal "L5")
		(12 "In5.Cu" signal "L6GND")
		(14 "In6.Cu" signal "L7VCC")
		(16 "In7.Cu" signal "L8VCC")
		(18 "In8.Cu" signal "L9GND")
		(20 "In9.Cu" signal "L10")
		(22 "In10.Cu" signal "L11GND")
		(24 "In11.Cu" signal "L12")
		(26 "In12.Cu" signal "L13GND")
		(2 "B.Cu" signal "BOTTOM")
		(9 "F.Adhes" user "F.Adhesive")
		(11 "B.Adhes" user "B.Adhesive")
		(13 "F.Paste" user "Package Geometry/Pastemask Top")
		(15 "B.Paste" user "Package Geometry/Pastemask Bottom")
		(5 "F.SilkS" user "Ref Des/Silkscreen Top")
		(7 "B.SilkS" user "Ref Des/Silkscreen Bottom")
		(1 "F.Mask" user "Board Geometry/Soldermask Top")
		(3 "B.Mask" user "Board Geometry/Soldermask Bottom")
		(17 "Dwgs.User" user "User.Drawings")
		(19 "Cmts.User" user "User.Comments")
		(21 "Eco1.User" user "User.Eco1")
		(23 "Eco2.User" user "User.Eco2")
		(25 "Edge.Cuts" user "Board Geometry/Outline")
		(27 "Margin" user)
		(31 "F.CrtYd" user "Package Geometry/Place Bound Top")
		(29 "B.CrtYd" user "Package Geometry/Place Bound Bottom")
		(35 "F.Fab" user "Ref Des/Assembly Top")
		(33 "B.Fab" user "Ref Des/Assembly Bottom")
	)
	(footprint ""
		(layer "F.Cu")
		(at 38.9128 -50.5714)
		(property "Reference" "R1E5"
			(at 0 0 0)
			(layer "F.SilkS")
			(hide yes)
			(effects
				(font
					(size 1.27 1.27)
				)
			)
		)
		(property "Value" ""
			(at 0 0 0)
			(layer "F.Fab")
			(effects
				(font
					(size 1.27 1.27)
				)
			)
		)
		(duplicate_pad_numbers_are_jumpers no)
		(fp_poly
			(pts
				(xy -0.2794 -0.1016) (xy 0.2794 -0.1016) (xy 0.2794 0.9906) (xy -0.2794 0.9906)
			)
			(stroke
				(width 0)
				(type default)
			)
			(fill no)
			(layer "F.CrtYd")
		)
		(fp_line
			(start -0.2794 -0.1016)
			(end -0.2794 0.9906)
			(stroke
				(width 0.1)
				(type default)
			)
			(layer "F.Fab")
		)
		(fp_line
			(start -0.2794 0.9906)
			(end 0.2794 0.9906)
			(stroke
				(width 0.1)
				(type default)
			)
			(layer "F.Fab")
		)
		(fp_line
			(start 0.2794 -0.1016)
			(end -0.2794 -0.1016)
			(stroke
				(width 0.1)
				(type default)
			)
			(layer "F.Fab")
		)
		(fp_line
			(start 0.2794 0.9906)
			(end 0.2794 -0.1016)
			(stroke
				(width 0.1)
				(type default)
			)
			(layer "F.Fab")
		)
		(pad "1" smd rect
			(at 0 0)
			(size 0.508 0.508)
			(layers "F.Cu" "F.Mask" "F.Paste")
			(net "VSENSE_PVCCIN_CPU1_P")
		)
		(pad "2" smd rect
			(at 0 0.889)
			(size 0.508 0.508)
			(layers "F.Cu" "F.Mask" "F.Paste")
			(net "VSENSE_PVCCIN_CPU1_N")
		)
		(zone
			(layer "F.Cu")
			(hatch none 0.5)
			(connect_pads
				(clearance 0)
			)
			(min_thickness 0.25)
			(keepout
				(tracks allowed)
				(vias not_allowed)
				(pads allowed)
				(copperpour not_allowed)
				(footprints allowed)
			)
			(placement
				(enabled no)
				(sheetname "")
			)
			(fill
				(thermal_gap 0.5)
				(thermal_bridge_width 0.5)
				(island_removal_mode 0)
			)
			(polygon
				(pts
					(xy 38.6588 -50.3174) (xy 39.1668 -50.3174) (xy 39.1668 -49.9364) (xy 38.6588 -49.9364)
				)
			)
		)
		(zone
			(layer "F.Cu")
			(hatch none 0.5)
			(connect_pads
				(clearance 0)
			)
			(min_thickness 0.25)
			(keepout
				(tracks not_allowed)
				(vias allowed)
				(pads allowed)
				(copperpour not_allowed)
				(footprints allowed)
			)
			(placement
				(enabled no)
				(sheetname "")
			)
			(fill
				(thermal_gap 0.5)
				(thermal_bridge_width 0.5)
				(island_removal_mode 0)
			)
			(polygon
				(pts
					(xy 38.6588 -49.9364) (xy 39.1668 -49.9364) (xy 39.1668 -50.3174) (xy 38.6588 -50.3174)
				)
			)
		)
	)
	(footprint ""
		(layer "F.Cu")
		(at 265.684 -79.6036 180)
		(property "Reference" "C5D17"
			(at 0 0 180)
			(layer "F.SilkS")
			(hide yes)
			(effects
				(font
					(size 1.27 1.27)
				)
			)
		)
		(property "Value" ""
			(at 0 0 180)
			(layer "F.Fab")
			(effects
				(font
					(size 1.27 1.27)
				)
			)
		)
		(duplicate_pad_numbers_are_jumpers no)
		(fp_poly
			(pts
				(xy -0.4953 -0.2032) (xy 0.4953 -0.2032) (xy 0.4953 1.6002) (xy -0.4953 1.6002)
			)
			(stroke
				(width 0)
				(type default)
			)
			(fill no)
			(layer "F.CrtYd")
		)
		(fp_line
			(start 0.4953 1.6002)
			(end -0.4953 1.6002)
			(stroke
				(width 0.1)
				(type default)
			)
			(layer "F.Fab")
		)
		(fp_line
			(start 0.4953 -0.2032)
			(end 0.4953 1.6002)
			(stroke
				(width 0.1)
				(type default)
			)
			(layer "F.Fab")
		)
		(fp_line
			(start -0.4953 1.6002)
			(end -0.4953 -0.2032)
			(stroke
				(width 0.1)
				(type default)
			)
			(layer "F.Fab")
		)
		(fp_line
			(start -0.4953 -0.2032)
			(end 0.4953 -0.2032)
			(stroke
				(width 0.1)
				(type default)
			)
			(layer "F.Fab")
		)
		(pad "1" smd rect
			(at 0 0 180)
			(size 0.762 0.889)
			(layers "F.Cu" "F.Mask" "F.Paste")
			(net "PVCCIN_CPU0")
		)
		(pad "2" smd rect
			(at 0 1.397 180)
			(size 0.762 0.889)
			(layers "F.Cu" "F.Mask" "F.Paste")
			(net "GND")
		)
		(zone
			(layer "F.Cu")
			(hatch none 0.5)
			(connect_pads
				(clearance 0)
			)
			(min_thickness 0.25)
			(keepout
				(tracks not_allowed)
				(vias allowed)
				(pads allowed)
				(copperpour not_allowed)
				(footprints allowed)
			)
			(placement
				(enabled no)
				(sheetname "")
			)
			(fill
				(thermal_gap 0.5)
				(thermal_bridge_width 0.5)
				(island_removal_mode 0)
			)
			(polygon
				(pts
					(xy 266.065 -80.0481) (xy 265.303 -80.0481) (xy 265.303 -80.5561) (xy 266.065 -80.5561)
				)
			)
		)
	)
	(footprint ""
		(layer "F.Cu")
		(at 409.3972 -116.6114 90)
		(property "Reference" "R8B20"
			(at 0 0 90)
			(layer "F.SilkS")
			(hide yes)
			(effects
				(font
					(size 1.27 1.27)
				)
			)
		)
		(property "Value" ""
			(at 0 0 90)
			(layer "F.Fab")
			(effects
				(font
					(size 1.27 1.27)
				)
			)
		)
		(duplicate_pad_numbers_are_jumpers no)
		(fp_poly
			(pts
				(xy -0.2794 -0.1016) (xy 0.2794 -0.1016) (xy 0.2794 0.9906) (xy -0.2794 0.9906)
			)
			(stroke
				(width 0)
				(type default)
			)
			(fill no)
			(layer "F.CrtYd")
		)
		(fp_line
			(start 0.2794 -0.1016)
			(end -0.2794 -0.1016)
			(stroke
				(width 0.1)
				(type default)
			)
			(layer "F.Fab")
		)
		(fp_line
			(start -0.2794 -0.1016)
			(end -0.2794 0.9906)
			(stroke
				(width 0.1)
				(type default)
			)
			(layer "F.Fab")
		)
		(fp_line
			(start 0.2794 0.9906)
			(end 0.2794 -0.1016)
			(stroke
				(width 0.1)
				(type default)
			)
			(layer "F.Fab")
		)
		(fp_line
			(start -0.2794 0.9906)
			(end 0.2794 0.9906)
			(stroke
				(width 0.1)
				(type default)
			)
			(layer "F.Fab")
		)
		(pad "1" smd rect
			(at 0 0 90)
			(size 0.508 0.508)
			(layers "F.Cu" "F.Mask" "F.Paste")
			(net "H_PMSYNC_CLK_24M_R")
		)
		(pad "2" smd rect
			(at 0 0.889 90)
			(size 0.508 0.508)
			(layers "F.Cu" "F.Mask" "F.Paste")
			(net "H_PMSYNC_CLK_24M")
		)
		(zone
			(layer "F.Cu")
			(hatch none 0.5)
			(connect_pads
				(clearance 0)
			)
			(min_thickness 0.25)
			(keepout
				(tracks allowed)
				(vias not_allowed)
				(pads allowed)
				(copperpour not_allowed)
				(footprints allowed)
			)
			(placement
				(enabled no)
				(sheetname "")
			)
			(fill
				(thermal_gap 0.5)
				(thermal_bridge_width 0.5)
				(island_removal_mode 0)
			)
			(polygon
				(pts
					(xy 409.6512 -116.3574) (xy 409.6512 -116.8654) (xy 410.0322 -116.8654) (xy 410.0322 -116.3574)
				)
			)
		)
		(zone
			(layer "F.Cu")
			(hatch none 0.5)
			(connect_pads
				(clearance 0)
			)
			(min_thickness 0.25)
			(keepout
				(tracks not_allowed)
				(vias allowed)
				(pads allowed)
				(copperpour not_allowed)
				(footprints allowed)
			)
			(placement
				(enabled no)
				(sheetname "")
			)
			(fill
				(thermal_gap 0.5)
				(thermal_bridge_width 0.5)
				(island_removal_mode 0)
			)
			(polygon
				(pts
					(xy 410.0322 -116.3574) (xy 410.0322 -116.8654) (xy 409.6512 -116.8654) (xy 409.6512 -116.3574)
				)
			)
		)
	)
)
